(kicad_pcb
	(version 20260206)
	(generator "pcbnew")
	(generator_version "10.0")
	(general
		(thickness 1.6)
		(legacy_teardrops no)
	)
	(paper "A4")
	(title_block
		(title "fcb — 12433-1M.1206WZS1330.brd")
		(comment 1 "Open Vault / Knox (Wiwynn) / footprints 372-378 of 495")
	)
	(layers
		(0 "F.Cu" signal "TOP")
		(4 "In1.Cu" signal "L2GND")
		(6 "In2.Cu" signal "L3VCC")
		(2 "B.Cu" signal "BOTTOM")
		(9 "F.Adhes" user "F.Adhesive")
		(11 "B.Adhes" user "B.Adhesive")
		(13 "F.Paste" user "Package Geometry/Pastemask Top")
		(15 "B.Paste" user "Package Geometry/Pastemask Bottom")
		(5 "F.SilkS" user "Ref Des/Silkscreen Top")
		(7 "B.SilkS" user "Ref Des/Silkscreen Bottom")
		(1 "F.Mask" user "Board Geometry/Soldermask Top")
		(3 "B.Mask" user "Board Geometry/Soldermask Bottom")
		(17 "Dwgs.User" user "User.Drawings")
		(19 "Cmts.User" user "User.Comments")
		(21 "Eco1.User" user "User.Eco1")
		(23 "Eco2.User" user "User.Eco2")
		(25 "Edge.Cuts" user "Board Geometry/Outline")
		(27 "Margin" user)
		(31 "F.CrtYd" user "Package Geometry/Place Bound Top")
		(29 "B.CrtYd" user "Package Geometry/Place Bound Bottom")
		(35 "F.Fab" user "Ref Des/Assembly Top")
		(33 "B.Fab" user "Ref Des/Assembly Bottom")
	)
	(footprint ""
		(layer "F.Cu")
		(at 42.05859 -162.643566 180)
		(property "Reference" "OSC1"
			(at 0 0 180)
			(layer "F.SilkS")
			(hide yes)
			(effects
				(font
					(size 1.27 1.27)
				)
			)
		)
		(property "Value" "OSC-33MHZ-7-GP"
			(at 0 -10.1092 180)
			(unlocked yes)
			(layer "F.Fab")
			(hide yes)
			(effects
				(font
					(size 1.016 1.016)
					(thickness 0.1524)
				)
			)
		)
		(property "Device Type" "SMD-OSC8H52"
			(at 0 -11.6332 180)
			(unlocked yes)
			(layer "F.Fab")
			(hide yes)
			(effects
				(font
					(size 1.016 1.016)
					(thickness 0.1524)
				)
			)
		)
		(duplicate_pad_numbers_are_jumpers no)
		(fp_line
			(start 2.7559 2.4638)
			(end -2.7559 2.4638)
			(stroke
				(width 0.1524)
				(type default)
			)
			(layer "F.SilkS")
		)
		(fp_line
			(start 2.7559 -2.4638)
			(end 2.7559 2.4638)
			(stroke
				(width 0.1524)
				(type default)
			)
			(layer "F.SilkS")
		)
		(fp_line
			(start -1.242822 2.55143)
			(end -2.852166 2.55143)
			(stroke
				(width 0.3302)
				(type default)
			)
			(layer "F.SilkS")
		)
		(fp_line
			(start -2.7559 2.4638)
			(end -2.7559 -2.4638)
			(stroke
				(width 0.1524)
				(type default)
			)
			(layer "F.SilkS")
		)
		(fp_line
			(start -2.7559 -2.4638)
			(end 2.7559 -2.4638)
			(stroke
				(width 0.1524)
				(type default)
			)
			(layer "F.SilkS")
		)
		(fp_line
			(start -2.852166 2.55143)
			(end -2.852166 1.131316)
			(stroke
				(width 0.3302)
				(type default)
			)
			(layer "F.SilkS")
		)
		(fp_poly
			(pts
				(xy -1.778 3.0734) (xy -1.2446 2.54) (xy -0.762 3.0734)
			)
			(stroke
				(width 0)
				(type default)
			)
			(fill yes)
			(layer "F.SilkS")
		)
		(fp_poly
			(pts
				(xy -3.0099 2.7178) (xy -3.0099 -2.7178) (xy 3.0099 -2.7178) (xy 3.0099 2.7178)
			)
			(stroke
				(width 0)
				(type default)
			)
			(fill no)
			(layer "F.CrtYd")
		)
		(fp_poly
			(pts
				(xy -3.0099 -2.7178) (xy 3.0099 -2.7178) (xy 3.0099 2.7178) (xy -3.0099 2.7178)
			)
			(stroke
				(width 0)
				(type default)
			)
			(fill no)
			(layer "F.Fab")
		)
		(pad "1" smd rect
			(at -1.46939 1.39954 180)
			(size 1.8034 1.6002)
			(layers "F.Cu" "F.Mask" "F.Paste")
			(net "OSC_TRI_S")
		)
		(pad "2" smd rect
			(at 1.46939 1.39954 180)
			(size 1.8034 1.6002)
			(layers "F.Cu" "F.Mask" "F.Paste")
			(net "GND")
		)
		(pad "3" smd rect
			(at 1.46939 -1.39954 180)
			(size 1.8034 1.6002)
			(layers "F.Cu" "F.Mask" "F.Paste")
			(net "NCT7904_CLK")
		)
		(pad "4" smd rect
			(at -1.46939 -1.39954 180)
			(size 1.8034 1.6002)
			(layers "F.Cu" "F.Mask" "F.Paste")
			(net "P3V3")
		)
		(zone
			(layer "F.Cu")
			(hatch none 0.5)
			(connect_pads
				(clearance 0)
			)
			(min_thickness 0.25)
			(keepout
				(tracks not_allowed)
				(vias allowed)
				(pads allowed)
				(copperpour not_allowed)
				(footprints allowed)
			)
			(placement
				(enabled no)
				(sheetname "")
			)
			(fill
				(thermal_gap 0.5)
				(thermal_bridge_width 0.5)
				(island_removal_mode 0)
			)
			(polygon
				(pts
					(xy 42.302938 -162.367468) (xy 42.302938 -162.919664) (xy 41.814242 -162.919664) (xy 41.814242 -162.367468)
				)
			)
		)
		(zone
			(layer "F.Cu")
			(hatch none 0.5)
			(connect_pads
				(clearance 0)
			)
			(min_thickness 0.25)
			(keepout
				(tracks allowed)
				(vias not_allowed)
				(pads allowed)
				(copperpour not_allowed)
				(footprints allowed)
			)
			(placement
				(enabled no)
				(sheetname "")
			)
			(fill
				(thermal_gap 0.5)
				(thermal_bridge_width 0.5)
				(island_removal_mode 0)
			)
			(polygon
				(pts
					(xy 42.62628 -164.843206) (xy 42.62628 -163.243006) (xy 44.42968 -163.243006) (xy 44.42968 -162.044126)
					(xy 42.62628 -162.044126) (xy 42.62628 -160.443926) (xy 41.4909 -160.443926) (xy 41.4909 -162.044126)
					(xy 39.6875 -162.044126) (xy 39.6875 -163.243006) (xy 41.4909 -163.243006) (xy 41.4909 -164.843206)
				)
			)
		)
	)
	(footprint ""
		(layer "F.Cu")
		(at 37.70249 -165.513766 180)
		(property "Reference" "R2"
			(at 0 0 180)
			(layer "F.SilkS")
			(hide yes)
			(effects
				(font
					(size 1.27 1.27)
				)
			)
		)
		(property "Value" "0R2J-2-GP"
			(at 0.064008 -3.993896 180)
			(unlocked yes)
			(layer "F.Fab")
			(hide yes)
			(effects
				(font
					(size 1.016 1.016)
					(thickness 0.1524)
				)
			)
		)
		(property "Device Type" "R402H16"
			(at 0.064008 -5.517896 180)
			(unlocked yes)
			(layer "F.Fab")
			(hide yes)
			(effects
				(font
					(size 1.016 1.016)
					(thickness 0.1524)
				)
			)
		)
		(duplicate_pad_numbers_are_jumpers no)
		(fp_line
			(start 0.508 -0.9398)
			(end -0.508 -0.9398)
			(stroke
				(width 0.1524)
				(type default)
			)
			(layer "F.SilkS")
		)
		(fp_line
			(start -0.508 -0.9398)
			(end -0.508 0.9398)
			(stroke
				(width 0.1524)
				(type default)
			)
			(layer "F.SilkS")
		)
		(fp_rect
			(start -0.508 0.9398)
			(end 0.508 -0.9398)
			(stroke
				(width 0)
				(type default)
			)
			(fill no)
			(layer "F.CrtYd")
		)
		(fp_rect
			(start -0.508 0.9398)
			(end 0.508 -0.9398)
			(stroke
				(width 0)
				(type default)
			)
			(fill no)
			(layer "F.Fab")
		)
		(pad "1" smd custom
			(at 0 -0.4445 180)
			(size 0.1397 0.1397)
			(layers "F.Cu" "F.Mask" "F.Paste")
			(net "I2C_C_SCL_NCT7904")
			(options
				(clearance outline)
				(anchor circle)
			)
			(primitives
				(gr_poly
					(pts
						(arc
							(start -0.1778 -0.2794)
							(mid -0.249642 -0.249642)
							(end -0.2794 -0.1778)
						)
						(arc
							(start -0.2794 0.1778)
							(mid -0.249642 0.249642)
							(end -0.1778 0.2794)
						)
						(arc
							(start 0.1778 0.2794)
							(mid 0.249642 0.249642)
							(end 0.2794 0.1778)
						)
						(arc
							(start 0.2794 -0.1778)
							(mid 0.249642 -0.249642)
							(end 0.1778 -0.2794)
						)
					)
					(width 0)
					(fill yes)
				)
			)
		)
		(pad "2" smd custom
			(at 0 0.4445 180)
			(size 0.1397 0.1397)
			(layers "F.Cu" "F.Mask" "F.Paste")
			(net "I2C_C_SCL")
			(options
				(clearance outline)
				(anchor circle)
			)
			(primitives
				(gr_poly
					(pts
						(arc
							(start -0.1778 -0.2794)
							(mid -0.249642 -0.249642)
							(end -0.2794 -0.1778)
						)
						(arc
							(start -0.2794 0.1778)
							(mid -0.249642 0.249642)
							(end -0.1778 0.2794)
						)
						(arc
							(start 0.1778 0.2794)
							(mid 0.249642 0.249642)
							(end 0.2794 0.1778)
						)
						(arc
							(start 0.2794 -0.1778)
							(mid 0.249642 -0.249642)
							(end 0.1778 -0.2794)
						)
					)
					(width 0)
					(fill yes)
				)
			)
		)
	)
	(footprint ""
		(layer "F.Cu")
		(at 31.7246 -184.2516)
		(property "Reference" "PR117"
			(at 0 0 0)
			(layer "F.SilkS")
			(hide yes)
			(effects
				(font
					(size 1.27 1.27)
				)
			)
		)
		(property "Value" "3K3R3F-GP"
			(at -0.0254 -2.5146 0)
			(unlocked yes)
			(layer "F.Fab")
			(hide yes)
			(effects
				(font
					(size 1.016 1.016)
					(thickness 0.1524)
				)
			)
		)
		(property "Device Type" "R603H22"
			(at -0.0254 -4.0386 0)
			(unlocked yes)
			(layer "F.Fab")
			(hide yes)
			(effects
				(font
					(size 1.016 1.016)
					(thickness 0.1524)
				)
			)
		)
		(duplicate_pad_numbers_are_jumpers no)
		(fp_line
			(start -0.4826 0)
			(end -0.2032 0)
			(stroke
				(width 0.2032)
				(type default)
			)
			(layer "F.SilkS")
		)
		(fp_line
			(start 0.2032 0)
			(end 0.4826 0)
			(stroke
				(width 0.2032)
				(type default)
			)
			(layer "F.SilkS")
		)
		(fp_rect
			(start -0.5842 1.3335)
			(end 0.5842 -1.3335)
			(stroke
				(width 0)
				(type default)
			)
			(fill no)
			(layer "F.CrtYd")
		)
		(fp_rect
			(start -0.5842 1.3335)
			(end 0.5842 -1.3335)
			(stroke
				(width 0)
				(type default)
			)
			(fill no)
			(layer "F.Fab")
		)
		(pad "1" smd custom
			(at 0 -0.762)
			(size 0.2159 0.2159)
			(layers "F.Cu" "F.Mask" "F.Paste")
			(net "P12V_AUX")
			(options
				(clearance outline)
				(anchor circle)
			)
			(primitives
				(gr_poly
					(pts
						(arc
							(start -0.3302 -0.4318)
							(mid -0.402042 -0.402042)
							(end -0.4318 -0.3302)
						)
						(arc
							(start -0.4318 0.3302)
							(mid -0.402042 0.402042)
							(end -0.3302 0.4318)
						)
						(arc
							(start 0.3302 0.4318)
							(mid 0.402042 0.402042)
							(end 0.4318 0.3302)
						)
						(arc
							(start 0.4318 -0.3302)
							(mid 0.402042 -0.402042)
							(end 0.3302 -0.4318)
						)
					)
					(width 0)
					(fill yes)
				)
			)
		)
		(pad "2" smd custom
			(at 0 0.762)
			(size 0.2159 0.2159)
			(layers "F.Cu" "F.Mask" "F.Paste")
			(net "P3V3_AUX_BJT_B")
			(options
				(clearance outline)
				(anchor circle)
			)
			(primitives
				(gr_poly
					(pts
						(arc
							(start -0.3302 -0.4318)
							(mid -0.402042 -0.402042)
							(end -0.4318 -0.3302)
						)
						(arc
							(start -0.4318 0.3302)
							(mid -0.402042 0.402042)
							(end -0.3302 0.4318)
						)
						(arc
							(start 0.3302 0.4318)
							(mid 0.402042 0.402042)
							(end 0.4318 0.3302)
						)
						(arc
							(start 0.4318 -0.3302)
							(mid 0.402042 -0.402042)
							(end 0.3302 -0.4318)
						)
					)
					(width 0)
					(fill yes)
				)
			)
		)
	)
	(footprint ""
		(layer "F.Cu")
		(at 30.3022 -224.3074)
		(property "Reference" "R138"
			(at 0 0 0)
			(layer "F.SilkS")
			(hide yes)
			(effects
				(font
					(size 1.27 1.27)
				)
			)
		)
		(property "Value" "0R2J-2-GP"
			(at 0.064008 -3.993896 0)
			(unlocked yes)
			(layer "F.Fab")
			(hide yes)
			(effects
				(font
					(size 1.016 1.016)
					(thickness 0.1524)
				)
			)
		)
		(property "Device Type" "R402H16"
			(at 0.064008 -5.517896 0)
			(unlocked yes)
			(layer "F.Fab")
			(hide yes)
			(effects
				(font
					(size 1.016 1.016)
					(thickness 0.1524)
				)
			)
		)
		(duplicate_pad_numbers_are_jumpers no)
		(fp_line
			(start -0.508 -0.9398)
			(end -0.508 0.9398)
			(stroke
				(width 0.1524)
				(type default)
			)
			(layer "F.SilkS")
		)
		(fp_line
			(start 0.508 -0.9398)
			(end -0.508 -0.9398)
			(stroke
				(width 0.1524)
				(type default)
			)
			(layer "F.SilkS")
		)
		(fp_rect
			(start -0.508 0.9398)
			(end 0.508 -0.9398)
			(stroke
				(width 0)
				(type default)
			)
			(fill no)
			(layer "F.CrtYd")
		)
		(fp_rect
			(start -0.508 0.9398)
			(end 0.508 -0.9398)
			(stroke
				(width 0)
				(type default)
			)
			(fill no)
			(layer "F.Fab")
		)
		(pad "1" smd custom
			(at 0 -0.4445)
			(size 0.1397 0.1397)
			(layers "F.Cu" "F.Mask" "F.Paste")
			(net "PWM_OUT_FAN3_NET")
			(options
				(clearance outline)
				(anchor circle)
			)
			(primitives
				(gr_poly
					(pts
						(arc
							(start -0.1778 -0.2794)
							(mid -0.249642 -0.249642)
							(end -0.2794 -0.1778)
						)
						(arc
							(start -0.2794 0.1778)
							(mid -0.249642 0.249642)
							(end -0.1778 0.2794)
						)
						(arc
							(start 0.1778 0.2794)
							(mid 0.249642 0.249642)
							(end 0.2794 0.1778)
						)
						(arc
							(start 0.2794 -0.1778)
							(mid 0.249642 -0.249642)
							(end 0.1778 -0.2794)
						)
					)
					(width 0)
					(fill yes)
				)
			)
		)
		(pad "2" smd custom
			(at 0 0.4445)
			(size 0.1397 0.1397)
			(layers "F.Cu" "F.Mask" "F.Paste")
			(net "PWM_OUT_FAN3")
			(options
				(clearance outline)
				(anchor circle)
			)
			(primitives
				(gr_poly
					(pts
						(arc
							(start -0.1778 -0.2794)
							(mid -0.249642 -0.249642)
							(end -0.2794 -0.1778)
						)
						(arc
							(start -0.2794 0.1778)
							(mid -0.249642 0.249642)
							(end -0.1778 0.2794)
						)
						(arc
							(start 0.1778 0.2794)
							(mid 0.249642 0.249642)
							(end 0.2794 0.1778)
						)
						(arc
							(start 0.2794 -0.1778)
							(mid 0.249642 -0.249642)
							(end 0.1778 -0.2794)
						)
					)
					(width 0)
					(fill yes)
				)
			)
		)
	)
	(footprint ""
		(layer "F.Cu")
		(at 14.3764 -49.0982)
		(property "Reference" "R186"
			(at 0 0 0)
			(layer "F.SilkS")
			(hide yes)
			(effects
				(font
					(size 1.27 1.27)
				)
			)
		)
		(property "Value" "0R2J-2-GP"
			(at 0.064008 -3.993896 0)
			(unlocked yes)
			(layer "F.Fab")
			(hide yes)
			(effects
				(font
					(size 1.016 1.016)
					(thickness 0.1524)
				)
			)
		)
		(property "Device Type" "R402H16"
			(at 0.064008 -5.517896 0)
			(unlocked yes)
			(layer "F.Fab")
			(hide yes)
			(effects
				(font
					(size 1.016 1.016)
					(thickness 0.1524)
				)
			)
		)
		(duplicate_pad_numbers_are_jumpers no)
		(fp_line
			(start -0.508 -0.9398)
			(end -0.508 0.9398)
			(stroke
				(width 0.1524)
				(type default)
			)
			(layer "F.SilkS")
		)
		(fp_line
			(start 0.508 -0.9398)
			(end -0.508 -0.9398)
			(stroke
				(width 0.1524)
				(type default)
			)
			(layer "F.SilkS")
		)
		(fp_rect
			(start -0.508 0.9398)
			(end 0.508 -0.9398)
			(stroke
				(width 0)
				(type default)
			)
			(fill no)
			(layer "F.CrtYd")
		)
		(fp_rect
			(start -0.508 0.9398)
			(end 0.508 -0.9398)
			(stroke
				(width 0)
				(type default)
			)
			(fill no)
			(layer "F.Fab")
		)
		(pad "1" smd custom
			(at 0 -0.4445)
			(size 0.1397 0.1397)
			(layers "F.Cu" "F.Mask" "F.Paste")
			(net "SD_LATCH_RELEASE_U")
			(options
				(clearance outline)
				(anchor circle)
			)
			(primitives
				(gr_poly
					(pts
						(arc
							(start -0.1778 -0.2794)
							(mid -0.249642 -0.249642)
							(end -0.2794 -0.1778)
						)
						(arc
							(start -0.2794 0.1778)
							(mid -0.249642 0.249642)
							(end -0.1778 0.2794)
						)
						(arc
							(start 0.1778 0.2794)
							(mid 0.249642 0.249642)
							(end 0.2794 0.1778)
						)
						(arc
							(start 0.2794 -0.1778)
							(mid 0.249642 -0.249642)
							(end 0.1778 -0.2794)
						)
					)
					(width 0)
					(fill yes)
				)
			)
		)
		(pad "2" smd custom
			(at 0 0.4445)
			(size 0.1397 0.1397)
			(layers "F.Cu" "F.Mask" "F.Paste")
			(net "D_LATCH_PRE#")
			(options
				(clearance outline)
				(anchor circle)
			)
			(primitives
				(gr_poly
					(pts
						(arc
							(start -0.1778 -0.2794)
							(mid -0.249642 -0.249642)
							(end -0.2794 -0.1778)
						)
						(arc
							(start -0.2794 0.1778)
							(mid -0.249642 0.249642)
							(end -0.1778 0.2794)
						)
						(arc
							(start 0.1778 0.2794)
							(mid 0.249642 0.249642)
							(end 0.2794 0.1778)
						)
						(arc
							(start 0.2794 -0.1778)
							(mid 0.249642 -0.249642)
							(end 0.1778 -0.2794)
						)
					)
					(width 0)
					(fill yes)
				)
			)
		)
	)
	(footprint ""
		(layer "F.Cu")
		(at 28.702 -381 180)
		(property "Reference" "PR18"
			(at 0 0 180)
			(layer "F.SilkS")
			(hide yes)
			(effects
				(font
					(size 1.27 1.27)
				)
			)
		)
		(property "Value" "10R2F-L-GP"
			(at 0.064008 -3.993896 180)
			(unlocked yes)
			(layer "F.Fab")
			(hide yes)
			(effects
				(font
					(size 1.016 1.016)
					(thickness 0.1524)
				)
			)
		)
		(property "Device Type" "R402H14"
			(at 0.064008 -5.517896 180)
			(unlocked yes)
			(layer "F.Fab")
			(hide yes)
			(effects
				(font
					(size 1.016 1.016)
					(thickness 0.1524)
				)
			)
		)
		(duplicate_pad_numbers_are_jumpers no)
		(fp_line
			(start 0.508 -0.9398)
			(end -0.508 -0.9398)
			(stroke
				(width 0.1524)
				(type default)
			)
			(layer "F.SilkS")
		)
		(fp_line
			(start -0.508 -0.9398)
			(end -0.508 0.9398)
			(stroke
				(width 0.1524)
				(type default)
			)
			(layer "F.SilkS")
		)
		(fp_rect
			(start -0.508 0.9398)
			(end 0.508 -0.9398)
			(stroke
				(width 0)
				(type default)
			)
			(fill no)
			(layer "F.CrtYd")
		)
		(fp_rect
			(start -0.508 0.9398)
			(end 0.508 -0.9398)
			(stroke
				(width 0)
				(type default)
			)
			(fill no)
			(layer "F.Fab")
		)
		(pad "1" smd custom
			(at 0 -0.4445 180)
			(size 0.1397 0.1397)
			(layers "F.Cu" "F.Mask" "F.Paste")
			(net "ADM1276_SENSE+")
			(options
				(clearance outline)
				(anchor circle)
			)
			(primitives
				(gr_poly
					(pts
						(arc
							(start -0.1778 -0.2794)
							(mid -0.249642 -0.249642)
							(end -0.2794 -0.1778)
						)
						(arc
							(start -0.2794 0.1778)
							(mid -0.249642 0.249642)
							(end -0.1778 0.2794)
						)
						(arc
							(start 0.1778 0.2794)
							(mid 0.249642 0.249642)
							(end 0.2794 0.1778)
						)
						(arc
							(start 0.2794 -0.1778)
							(mid 0.249642 -0.249642)
							(end 0.1778 -0.2794)
						)
					)
					(width 0)
					(fill yes)
				)
			)
		)
		(pad "2" smd custom
			(at 0 0.4445 180)
			(size 0.1397 0.1397)
			(layers "F.Cu" "F.Mask" "F.Paste")
			(net "SENSE+_R3")
			(options
				(clearance outline)
				(anchor circle)
			)
			(primitives
				(gr_poly
					(pts
						(arc
							(start -0.1778 -0.2794)
							(mid -0.249642 -0.249642)
							(end -0.2794 -0.1778)
						)
						(arc
							(start -0.2794 0.1778)
							(mid -0.249642 0.249642)
							(end -0.1778 0.2794)
						)
						(arc
							(start 0.1778 0.2794)
							(mid 0.249642 0.249642)
							(end 0.2794 0.1778)
						)
						(arc
							(start 0.2794 -0.1778)
							(mid 0.249642 -0.249642)
							(end 0.1778 -0.2794)
						)
					)
					(width 0)
					(fill yes)
				)
			)
		)
	)
	(footprint ""
		(layer "F.Cu")
		(at 24.003 -248.793)
		(property "Reference" "PR56"
			(at 0 0 0)
			(layer "F.SilkS")
			(hide yes)
			(effects
				(font
					(size 1.27 1.27)
				)
			)
		)
		(property "Value" "22K1R3F-GP"
			(at -0.0254 -2.5146 0)
			(unlocked yes)
			(layer "F.Fab")
			(hide yes)
			(effects
				(font
					(size 1.016 1.016)
					(thickness 0.1524)
				)
			)
		)
		(property "Device Type" "R603H22"
			(at -0.0254 -4.0386 0)
			(unlocked yes)
			(layer "F.Fab")
			(hide yes)
			(effects
				(font
					(size 1.016 1.016)
					(thickness 0.1524)
				)
			)
		)
		(duplicate_pad_numbers_are_jumpers no)
		(fp_line
			(start -0.4826 0)
			(end -0.2032 0)
			(stroke
				(width 0.2032)
				(type default)
			)
			(layer "F.SilkS")
		)
		(fp_line
			(start 0.2032 0)
			(end 0.4826 0)
			(stroke
				(width 0.2032)
				(type default)
			)
			(layer "F.SilkS")
		)
		(fp_rect
			(start -0.5842 1.3335)
			(end 0.5842 -1.3335)
			(stroke
				(width 0)
				(type default)
			)
			(fill no)
			(layer "F.CrtYd")
		)
		(fp_rect
			(start -0.5842 1.3335)
			(end 0.5842 -1.3335)
			(stroke
				(width 0)
				(type default)
			)
			(fill no)
			(layer "F.Fab")
		)
		(pad "1" smd custom
			(at 0 -0.762)
			(size 0.2159 0.2159)
			(layers "F.Cu" "F.Mask" "F.Paste")
			(net "P3V3_FB")
			(options
				(clearance outline)
				(anchor circle)
			)
			(primitives
				(gr_poly
					(pts
						(arc
							(start -0.3302 -0.4318)
							(mid -0.402042 -0.402042)
							(end -0.4318 -0.3302)
						)
						(arc
							(start -0.4318 0.3302)
							(mid -0.402042 0.402042)
							(end -0.3302 0.4318)
						)
						(arc
							(start 0.3302 0.4318)
							(mid 0.402042 0.402042)
							(end 0.4318 0.3302)
						)
						(arc
							(start 0.4318 -0.3302)
							(mid 0.402042 -0.402042)
							(end 0.3302 -0.4318)
						)
					)
					(width 0)
					(fill yes)
				)
			)
		)
		(pad "2" smd custom
			(at 0 0.762)
			(size 0.2159 0.2159)
			(layers "F.Cu" "F.Mask" "F.Paste")
			(net "GND")
			(options
				(clearance outline)
				(anchor circle)
			)
			(primitives
				(gr_poly
					(pts
						(arc
							(start -0.3302 -0.4318)
							(mid -0.402042 -0.402042)
							(end -0.4318 -0.3302)
						)
						(arc
							(start -0.4318 0.3302)
							(mid -0.402042 0.402042)
							(end -0.3302 0.4318)
						)
						(arc
							(start 0.3302 0.4318)
							(mid 0.402042 0.402042)
							(end 0.4318 0.3302)
						)
						(arc
							(start 0.4318 -0.3302)
							(mid 0.402042 -0.402042)
							(end 0.3302 -0.4318)
						)
					)
					(width 0)
					(fill yes)
				)
			)
		)
	)
)
